FILE_TYPE = CONNECTIVITY;
{Allegro Design Entry HDL 17.4-2019 S026 (4007227) 1/17/2022}
"PAGE_NUMBER" = 315;
0"NC";
1"GND\g";
2"GND\g";
3"GND\g";
4"GND\g";
5"GND\g";
6"P3V3_AUX\g";
7"GND\g";
8"GND\g";
9"P1V8_AUX_ENABLE";
10"P3V3_AUX\g";
11"GND\g";
12"GND\g";
13"GND\g";
14"P1V8_AUX\g";
15"P12V_AUX\g";
16"GND\g";
17"P1V8_AUX_CS";
18"P1V8_AUX_REF";
19"PWRGD_P1V8_AUX";
20"SW_P1V8_AUX_BT_R";
21"SW_P1V8_AUX_PH";
22"SW_P1V8_AUX_BT";
23"P1V8_AUX_FB";
24"SW_P12V_AUX_P1V8_AUX_FLT";
25"PWRGD_P3V3_AUX";
26"P1V8_AUX_MODE";
27"P1V8_AUX_VCC";
28"PWRGD_P1V8_AUX_R";
%"UNIVERSAL_POWER"
"1","(-3200,1725)","0","pure_quanta_power","I1";
;
HDL_POWER"P3V3_AUX"
CDS_LIB"pure_quanta_power";
"A"10;
%"Q_CAP"
"1","(-2725,2525)","0","pure_quanta","I10";
;
LOCATION"PC6014"
$SEC"1"
CDS_SEC"1"
MATERIAL"X6S"
PACK_TYPE"C0805"
VALUE"22UF"
TOLERANCE"20%"
VOLTAGE"16V"
CDS_LIB"pure_quanta"
PART_NUMBER"CH6223MEA01";
"B"
$PN"2"16;
"A"
$PN"1"24;
%"GND"
"1","(-2025,775)","0","pure_quanta_power","I11";
;
SIZE"1B"
CDS_LIB"pure_quanta_power"
HDL_POWER"GND";
"A<SIZE-1..0>\NAC"1;
%"Q_RES"
"2","(-2025,975)","0","pure_quanta","I12";
;
LOCATION"PR6003"
$SEC"1"
CDS_SEC"1"
PACK_TYPE"0402LF"
WATTAGE"1/16W"
MATERIAL"CHIP"
VALUE"10K"
TOLERANCE"1%"
CDS_LIB"pure_quanta"
PART_NUMBER"CS31002FB08";
"A"
$PN"1"17;
"B"
$PN"2"1;
%"Q_CAP"
"1","(-2225,1375)","0","pure_quanta","I13";
;
LOCATION"PC6008"
$SEC"1"
CDS_SEC"1"
VALUE"1UF"
VOLTAGE"25V"
MATERIAL"X6S"
TOLERANCE"10%"
PACK_TYPE"C0402"
CDS_LIB"pure_quanta"
PART_NUMBER"CH5104KEB02";
"B"
$PN"2"2;
"A"
$PN"1"27;
%"GND"
"1","(-2225,1175)","0","pure_quanta_power","I14";
;
SIZE"1B"
CDS_LIB"pure_quanta_power"
HDL_POWER"GND";
"A<SIZE-1..0>\NAC"2;
%"Q_RES"
"1","(-2300,1825)","0","pure_quanta","I15";
;
LOCATION"PR6006"
$SEC"1"
CDS_SEC"1"
TOLERANCE"1%"
MATERIAL"CHIP"
VALUE"60.4K"
WATTAGE"1/16W"
PACK_TYPE"0402LF"
CDS_LIB"pure_quanta"
PART_NUMBER"CS36042FB04";
"B"
$PN"2"26;
"A"
$PN"1"12;
%"GND"
"1","(-525,775)","0","pure_quanta_power","I17";
;
SIZE"1B"
CDS_LIB"pure_quanta_power"
HDL_POWER"GND";
"A<SIZE-1..0>\NAC"11;
%"MPQ8626GDZ"
"1","(-1075,1850)","0","pure_quanta","I18";
;
LOCATION"PU6000"
SEC"1"
PART_TYPE"SMLF"
MATERIAL"IC"
VALUE"MPQ8626GD-Z"
NEEDS_NO_SIZE"TRUE"
CDS_LMAN_SYM_OUTLINE"-250,725,250,-725"
CDS_LIB"pure_quanta"
SEC_TYPE""
PART_NUMBER"AL008626000";
"SW1"
$PN"2"21;
"CS"
$PN"4"17;
"MODE"
$PN"12"26;
"TRK_REF"
$PN"8"18;
"SW2"
$PN"11"21;
"PGND1"
$PN"1"5;
"VCC"
$PN"13"27;
"AGND"
$PN"7"11;
"FB"
$PN"6"23;
"BST"
$PN"10"22;
"EN"
$PN"5"9;
"PGND2"
$PN"14"11;
"PGOOD"
$PN"9"19;
"VIN"
$PN"3"24;
%"Q_CAP"
"1","(-2125,2525)","0","pure_quanta","I19";
;
LOCATION"PC6010"
$SEC"1"
CDS_SEC"1"
TOLERANCE"10%"
MATERIAL"X6S"
VALUE"1UF"
VOLTAGE"25V"
PACK_TYPE"C0402"
CDS_LIB"pure_quanta"
PART_NUMBER"CH5104KEB02";
"B"
$PN"2"16;
"A"
$PN"1"24;
%"Q_RES"
"2","(-2825,1575)","3","pure_quanta","I2";
;
LOCATION"R6242"
$SEC"1"
CDS_SEC"1"
WATTAGE"1/16W"
TOLERANCE"5%"
VALUE"0"
MATERIAL"CHIP"
PACK_TYPE"0402LF"
CDS_LIB"pure_quanta"
PART_NUMBER"CS00002JB13";
"A"
$PN"1"10;
"B"
$PN"2"27;
%"GND"
"1","(-125,775)","0","pure_quanta_power","I20";
;
SIZE"1B"
CDS_LIB"pure_quanta_power"
HDL_POWER"GND";
"A<SIZE-1..0>\NAC"3;
%"Q_CAP"
"1","(-125,1050)","0","pure_quanta","I21";
;
LOCATION"PC384"
$SEC"1"
CDS_SEC"1"
MATERIAL"X7R"
TOLERANCE"10%"
PACK_TYPE"0402"
VOLTAGE"50V"
VALUE"3300PF"
CDS_LIB"pure_quanta"
PART_NUMBER"TMP_QCH2336K1B12";
"B"
$PN"2"3;
"A"
$PN"1"18;
%"GND"
"1","(475,675)","0","pure_quanta_power","I22";
;
SIZE"1B"
CDS_LIB"pure_quanta_power"
HDL_POWER"GND";
"A<SIZE-1..0>\NAC"4;
%"Q_RES"
"2","(475,900)","0","pure_quanta","I23";
;
LOCATION"PR6010"
$SEC"1"
CDS_SEC"1"
PACK_TYPE"0402LF"
MATERIAL"CHIP"
WATTAGE"1/16W"
VALUE"10K"
TOLERANCE"1%"
CDS_LIB"pure_quanta"
PART_NUMBER"CS31002FB08";
"A"
$PN"1"23;
"B"
$PN"2"4;
%"GND"
"1","(175,1275)","0","pure_quanta_power","I24";
;
SIZE"1B"
CDS_LIB"pure_quanta_power"
HDL_POWER"GND";
"A<SIZE-1..0>\NAC"5;
%"Q_INDUCTOR"
"1","(825,2050)","0","pure_quanta","I25";
;
LOCATION"PL6000"
$SEC"1"
CDS_SEC"1"
MATERIAL"IND"
PACK_TYPE"SMLF"
VALUE"3.3UH/6A"
NEEDS_NO_SIZE"TRUE"
CDS_LIB"pure_quanta"
PART_NUMBER"CV-3360MZ07";
"1"
$PN"1"21;
"2"
$PN"2"14;
%"Q_CAP"
"2","(1525,825)","0","pure_quanta","I26";
;
LOCATION"PC6019"
$SEC"1"
CDS_SEC"1"
MATERIAL"X7R"
VOLTAGE"50V"
PACK_TYPE"0402"
VALUE"330PF"
TOLERANCE"10%"
CDS_LIB"pure_quanta"
PART_NUMBER"CH1336K1B02";
"A"
$PN"1"23;
"B"
$PN"2"14;
%"Q_CAP"
"1","(1025,1825)","0","pure_quanta","I27";
;
LOCATION"PC6021"
$SEC"1"
CDS_SEC"1"
VOLTAGE"50V"
PACK_TYPE"C0402"
VALUE"100NF"
MATERIAL"X7R"
TOLERANCE"10%"
CDS_LIB"pure_quanta"
PART_NUMBER"CH4106K1B01";
"B"
$PN"2"13;
"A"
$PN"1"14;
%"Q_RES"
"1","(1525,1250)","0","pure_quanta","I28";
;
LOCATION"PR6007"
$SEC"1"
CDS_SEC"1"
TOLERANCE"1%"
VALUE"20K"
WATTAGE"1/16W"
PACK_TYPE"0402LF"
MATERIAL"CHIP"
CDS_LIB"pure_quanta"
PART_NUMBER"CS32002FB06";
"B"
$PN"2"14;
"A"
$PN"1"23;
%"Q_CAP"
"1","(1400,1825)","0","pure_quanta","I29";
;
LOCATION"PC865"
$SEC"1"
CDS_SEC"1"
TOLERANCE"20%"
MATERIAL"X6S"
PACK_TYPE"C0805"
VOLTAGE"4V"
VALUE"22UF"
CDS_LIB"pure_quanta"
PART_NUMBER"CH622KMEA03";
"B"
$PN"2"13;
"A"
$PN"1"14;
%"GND"
"1","(-2725,1675)","0","pure_quanta_power","I3";
;
SIZE"1B"
CDS_LIB"pure_quanta_power"
HDL_POWER"GND";
"A<SIZE-1..0>\NAC"12;
%"Q_CAP"
"1","(350,2200)","0","pure_quanta","I30";
;
LOCATION"PC641"
$SEC"1"
CDS_SEC"1"
VOLTAGE"25V"
TOLERANCE"10%"
VALUE"0.22UF"
MATERIAL"X7R"
PACK_TYPE"C0402"
CDS_LIB"pure_quanta"
PART_NUMBER"CH4224K1B01";
"B"
$PN"2"21;
"A"
$PN"1"20;
%"Q_RES"
"2","(25,2825)","0","pure_quanta","I32";
;
LOCATION"R6243"
$SEC"1"
CDS_SEC"1"
VALUE"10K"
TOLERANCE"1%"
PACK_TYPE"0402LF"
MATERIAL"CHIP"
WATTAGE"1/16W"
CDS_LIB"pure_quanta"
PART_NUMBER"CS31002FB08";
"A"
$PN"1"6;
"B"
$PN"2"19;
%"UNIVERSAL_POWER"
"1","(25,3125)","0","pure_quanta_power","I33";
;
HDL_POWER"P3V3_AUX"
CDS_LIB"pure_quanta_power";
"A"6;
%"Q_CAP"
"1","(1775,1825)","0","pure_quanta","I34";
;
LOCATION"PC866"
$SEC"1"
CDS_SEC"1"
PACK_TYPE"C0805"
MATERIAL"X6S"
TOLERANCE"20%"
VOLTAGE"4V"
VALUE"22UF"
CDS_LIB"pure_quanta"
PART_NUMBER"CH622KMEA03";
"B"
$PN"2"13;
"A"
$PN"1"14;
%"GND"
"1","(2075,1475)","0","pure_quanta_power","I35";
;
SIZE"1B"
CDS_LIB"pure_quanta_power"
HDL_POWER"GND";
"A<SIZE-1..0>\NAC"13;
%"Q_CAP"
"1","(2275,1825)","0","pure_quanta","I36";
;
LOCATION"PC867"
$SEC"1"
CDS_SEC"1"
PACK_TYPE"C0805"
MATERIAL"X6S"
TOLERANCE"20%"
VALUE"22UF"
VOLTAGE"4V"
CDS_LIB"pure_quanta"
PART_NUMBER"CH622KMEA03";
"B"
$PN"2"13;
"A"
$PN"1"14;
%"Q_CAP"
"1","(2775,1825)","0","pure_quanta","I37";
;
LOCATION"PC850"
$SEC"1"
CDS_SEC"1"
VOLTAGE"4V"
TOLERANCE"20%"
PACK_TYPE"C0805"
VALUE"22UF"
MATERIAL"X6S"
CDS_LIB"pure_quanta"
PART_NUMBER"CH622KMEA03";
"B"
$PN"2"13;
"A"
$PN"1"14;
%"UNIVERSAL_POWER"
"1","(2275,2175)","0","pure_quanta_power","I38";
;
HDL_POWER"P1V8_AUX"
CDS_LIB"pure_quanta_power";
"A"14;
%"GND"
"1","(-4125,2275)","0","pure_quanta_power","I4";
;
SIZE"1B"
CDS_LIB"pure_quanta_power"
HDL_POWER"GND";
"A<SIZE-1..0>\NAC"7;
%"Q_RES"
"1","(-3900,2025)","0","pure_quanta","I40";
;
LOCATION"R6119"
SEC"1"
VALUE"0"
TOLERANCE"5%"
WATTAGE"1/16W"
PACK_TYPE"0402LF"
MATERIAL"CHIP"
SEC_TYPE"0402LF"
CDS_LIB"pure_quanta"
PART_NUMBER"CS00002JB13";
"B"
$PN"2"9;
"A"
$PN"1"25;
%"Q_CAP"
"1","(-3525,1575)","2","pure_quanta","I41";
;
LOCATION"C345"
$SEC"1"
CDS_SEC"1"
TOLERANCE"10%"
MATERIAL"EMPTY"
PACK_TYPE"0402"
VOLTAGE"25V"
VALUE"0.1UF"
CDS_LIB"pure_quanta"
PART_NUMBER"CH4104K1B00";
"B"
$PN"2"8;
"A"
$PN"1"9;
%"GND"
"1","(-3525,1125)","0","pure_quanta_power","I42";
;
SIZE"1B"
CDS_LIB"pure_quanta_power"
HDL_POWER"GND";
"A<SIZE-1..0>\NAC"8;
%"Q_RES"
"1","(350,2525)","0","pure_quanta","I44";
;
LOCATION"R214"
$SEC"1"
CDS_SEC"1"
VALUE"33"
CDS_LIB"pure_quanta"
PACK_TYPE"0402LF"
TOLERANCE"5%"
MATERIAL"CHIP"
WATTAGE"1/16W"
BOM_COST"MEM"
PART_NUMBER"CS03302JB10";
"B"
$PN"2"28;
"A"
$PN"1"19;
%"Q_RES"
"1","(-100,2325)","0","pure_quanta","I45";
;
LOCATION"PR8003"
SEC"1"
TOLERANCE"1%"
MATERIAL"CHIP"
PACK_TYPE"0402LF"
VALUE"2.2"
CDS_LIB"pure_quanta"
SEC_TYPE"0402LF"
WATTAGE"1/16W"
PART_NUMBER"CS-2202FB01";
"B"
$PN"2"20;
"A"
$PN"1"22;
%"Q_CAP"
"1","(-4125,2525)","0","pure_quanta","I5";
;
LOCATION"PC6020"
$SEC"1"
CDS_SEC"1"
MATERIAL"X7R"
TOLERANCE"10%"
VOLTAGE"50V"
VALUE"100NF"
PACK_TYPE"C0402"
CDS_LIB"pure_quanta"
PART_NUMBER"CH4106K1B01";
"B"
$PN"2"7;
"A"
$PN"1"15;
%"UNIVERSAL_POWER"
"1","(-4125,2875)","0","pure_quanta_power","I6";
;
HDL_POWER"P12V_AUX"
CDS_LIB"pure_quanta_power";
"A"15;
%"Q_INDUCTOR"
"1","(-3625,2750)","0","pure_quanta","I7";
;
LOCATION"PL6002"
$SEC"1"
CDS_SEC"1"
VALUE"BLM18SN220TN1D/8000MA"
PACK_TYPE"SMLF"
MATERIAL"IND"
NEEDS_NO_SIZE"TRUE"
CDS_LIB"pure_quanta"
PART_NUMBER"CX220TN1001";
"1"
$PN"1"15;
"2"
$PN"2"24;
%"Q_CAP"
"1","(-3325,2525)","0","pure_quanta","I8";
;
LOCATION"PC6012"
$SEC"1"
CDS_SEC"1"
TOLERANCE"20%"
VOLTAGE"16V"
VALUE"22UF"
MATERIAL"X6S"
PACK_TYPE"C0805"
CDS_LIB"pure_quanta"
PART_NUMBER"CH6223MEA01";
"B"
$PN"2"16;
"A"
$PN"1"24;
%"GND"
"1","(-2675,2175)","0","pure_quanta_power","I9";
;
SIZE"1B"
CDS_LIB"pure_quanta_power"
HDL_POWER"GND";
"A<SIZE-1..0>\NAC"16;
END.
